(kicad_pcb
	(version 20260206)
	(generator "pcbnew")
	(generator_version "10.0")
	(general
		(thickness 1.6)
		(legacy_teardrops no)
	)
	(paper "A4")
	(title_block
		(title "timecard-production-celestica-r4006 — R4006-B0001-02_R01.brd")
		(comment 1 "Time Appliance Project (Time Card) / footprints 57-62 of 1113")
	)
	(layers
		(0 "F.Cu" signal "TOP")
		(4 "In1.Cu" signal "L02_GND1")
		(6 "In2.Cu" signal "L03_SIG1")
		(8 "In3.Cu" signal "L04_GND2")
		(10 "In4.Cu" signal "L05_VCC1")
		(12 "In5.Cu" signal "L06_VCC2")
		(14 "In6.Cu" signal "L07_GND3")
		(16 "In7.Cu" signal "L08_SIG2")
		(18 "In8.Cu" signal "L09_GND4")
		(2 "B.Cu" signal "BOTTOM")
		(9 "F.Adhes" user "F.Adhesive")
		(11 "B.Adhes" user "B.Adhesive")
		(13 "F.Paste" user "Package Geometry/Pastemask Top")
		(15 "B.Paste" user "Package Geometry/Pastemask Bottom")
		(5 "F.SilkS" user "Ref Des/Silkscreen Top")
		(7 "B.SilkS" user "Ref Des/Silkscreen Bottom")
		(1 "F.Mask" user "Board Geometry/Soldermask Top")
		(3 "B.Mask" user "Board Geometry/Soldermask Bottom")
		(17 "Dwgs.User" user "User.Drawings")
		(19 "Cmts.User" user "User.Comments")
		(21 "Eco1.User" user "User.Eco1")
		(23 "Eco2.User" user "User.Eco2")
		(25 "Edge.Cuts" user "Board Geometry/Outline")
		(27 "Margin" user)
		(31 "F.CrtYd" user "Package Geometry/Place Bound Top")
		(29 "B.CrtYd" user "Package Geometry/Place Bound Bottom")
		(35 "F.Fab" user "Ref Des/Assembly Top")
		(33 "B.Fab" user "Ref Des/Assembly Bottom")
	)
	(footprint ""
		(layer "F.Cu")
		(at 10.5664 -39.318692 90)
		(property "Reference" "R386"
			(at 0.178308 1.02235 90)
			(unlocked yes)
			(layer "F.SilkS")
			(effects
				(font
					(size 0.635 0.4064)
					(thickness 0.1524)
				)
			)
		)
		(property "Value" "VAL*"
			(at 0.02032 2.13233 90)
			(unlocked yes)
			(layer "F.Fab")
			(hide yes)
			(effects
				(font
					(size 0.7874 0.5842)
					(thickness 0.1524)
				)
			)
		)
		(property "Tolerance" "TOL*"
			(at 0.044704 3.05435 90)
			(unlocked yes)
			(layer "Cmts.User")
			(hide yes)
			(effects
				(font
					(size 0.7874 0.5842)
					(thickness 0.1524)
				)
			)
		)
		(property "User Part Number" "PARTNUM*"
			(at 0.02032 4.024884 90)
			(unlocked yes)
			(layer "Cmts.User")
			(hide yes)
			(effects
				(font
					(size 0.7874 0.5842)
					(thickness 0.1524)
				)
			)
		)
		(property "Device Type" "RESISTOR-G155-133R0-01,33OHM,1%"
			(at 0.008382 1.210564 90)
			(unlocked yes)
			(layer "F.Fab")
			(hide yes)
			(effects
				(font
					(size 0.7874 0.5842)
					(thickness 0.1524)
				)
			)
		)
		(duplicate_pad_numbers_are_jumpers no)
		(fp_line
			(start 1.143 -0.5588)
			(end -1.143 -0.5588)
			(stroke
				(width 0.1)
				(type default)
			)
			(layer "F.SilkS")
		)
		(fp_line
			(start -1.143 -0.5588)
			(end -1.143 0.5588)
			(stroke
				(width 0.1)
				(type default)
			)
			(layer "F.SilkS")
		)
		(fp_line
			(start 1.143 0.5588)
			(end 1.143 -0.5588)
			(stroke
				(width 0.1)
				(type default)
			)
			(layer "F.SilkS")
		)
		(fp_line
			(start -1.143 0.5588)
			(end 1.143 0.5588)
			(stroke
				(width 0.1)
				(type default)
			)
			(layer "F.SilkS")
		)
		(fp_rect
			(start -1.143 -0.5588)
			(end 1.143 0.5588)
			(stroke
				(width 0)
				(type default)
			)
			(fill no)
			(layer "F.CrtYd")
		)
		(fp_line
			(start 0.508 -0.3048)
			(end -0.508 -0.3048)
			(stroke
				(width 0.1)
				(type default)
			)
			(layer "F.Fab")
		)
		(fp_line
			(start -0.508 -0.3048)
			(end -0.508 0.3048)
			(stroke
				(width 0.1)
				(type default)
			)
			(layer "F.Fab")
		)
		(fp_line
			(start 0.508 0.3048)
			(end 0.508 -0.3048)
			(stroke
				(width 0.1)
				(type default)
			)
			(layer "F.Fab")
		)
		(fp_line
			(start -0.508 0.3048)
			(end 0.508 0.3048)
			(stroke
				(width 0.1)
				(type default)
			)
			(layer "F.Fab")
		)
		(pad "1" smd rect
			(at -0.5334 0 90)
			(size 0.7112 0.6096)
			(layers "F.Cu" "F.Mask" "F.Paste")
			(net "SMA1_LED_GREEN_N")
		)
		(pad "2" smd rect
			(at 0.5334 0 90)
			(size 0.7112 0.6096)
			(layers "F.Cu" "F.Mask" "F.Paste")
			(net "UNNAMED_14_LED4PV14_I265_4")
		)
		(zone
			(layer "F.Cu")
			(hatch none 0.5)
			(connect_pads
				(clearance 0)
			)
			(min_thickness 0.25)
			(keepout
				(tracks not_allowed)
				(vias allowed)
				(pads allowed)
				(copperpour not_allowed)
				(footprints allowed)
			)
			(placement
				(enabled no)
				(sheetname "")
			)
			(fill
				(thermal_gap 0.5)
				(thermal_bridge_width 0.5)
				(island_removal_mode 0)
			)
			(polygon
				(pts
					(xy 10.2616 -39.242492) (xy 10.8712 -39.242492) (xy 10.8712 -39.394892) (xy 10.2616 -39.394892)
				)
			)
		)
		(zone
			(layer "F.Cu")
			(hatch none 0.5)
			(connect_pads
				(clearance 0)
			)
			(min_thickness 0.25)
			(keepout
				(tracks allowed)
				(vias not_allowed)
				(pads allowed)
				(copperpour not_allowed)
				(footprints allowed)
			)
			(placement
				(enabled no)
				(sheetname "")
			)
			(fill
				(thermal_gap 0.5)
				(thermal_bridge_width 0.5)
				(island_removal_mode 0)
			)
			(polygon
				(pts
					(xy 10.2616 -39.242492) (xy 10.8712 -39.242492) (xy 10.8712 -39.394892) (xy 10.2616 -39.394892)
				)
			)
		)
	)
	(footprint ""
		(layer "F.Cu")
		(at 79.883 -43.053)
		(property "Reference" "R96"
			(at 0 13.88237 0)
			(unlocked yes)
			(layer "F.SilkS")
			(effects
				(font
					(size 0.7874 0.5842)
					(thickness 0.1524)
				)
			)
		)
		(property "Value" "VAL*"
			(at 0.02032 2.13233 0)
			(unlocked yes)
			(layer "F.Fab")
			(hide yes)
			(effects
				(font
					(size 0.7874 0.5842)
					(thickness 0.1524)
				)
			)
		)
		(property "Device Type" "RESISTOR-G155-133R0-01,33OHM,1%"
			(at 0.008382 1.210564 0)
			(unlocked yes)
			(layer "F.Fab")
			(hide yes)
			(effects
				(font
					(size 0.7874 0.5842)
					(thickness 0.1524)
				)
			)
		)
		(property "User Part Number" "PARTNUM*"
			(at 0.02032 4.024884 0)
			(unlocked yes)
			(layer "Cmts.User")
			(hide yes)
			(effects
				(font
					(size 0.7874 0.5842)
					(thickness 0.1524)
				)
			)
		)
		(property "Tolerance" "TOL*"
			(at 0.044704 3.05435 0)
			(unlocked yes)
			(layer "Cmts.User")
			(hide yes)
			(effects
				(font
					(size 0.7874 0.5842)
					(thickness 0.1524)
				)
			)
		)
		(duplicate_pad_numbers_are_jumpers no)
		(fp_line
			(start -1.143 -0.5588)
			(end -1.143 0.5588)
			(stroke
				(width 0.1)
				(type default)
			)
			(layer "F.SilkS")
		)
		(fp_line
			(start -1.143 0.5588)
			(end 1.143 0.5588)
			(stroke
				(width 0.1)
				(type default)
			)
			(layer "F.SilkS")
		)
		(fp_line
			(start 1.143 -0.5588)
			(end -1.143 -0.5588)
			(stroke
				(width 0.1)
				(type default)
			)
			(layer "F.SilkS")
		)
		(fp_line
			(start 1.143 0.5588)
			(end 1.143 -0.5588)
			(stroke
				(width 0.1)
				(type default)
			)
			(layer "F.SilkS")
		)
		(fp_rect
			(start -1.143 0.5588)
			(end 1.143 -0.5588)
			(stroke
				(width 0)
				(type default)
			)
			(fill no)
			(layer "F.CrtYd")
		)
		(fp_line
			(start -0.508 -0.3048)
			(end -0.508 0.3048)
			(stroke
				(width 0.1)
				(type default)
			)
			(layer "F.Fab")
		)
		(fp_line
			(start -0.508 0.3048)
			(end 0.508 0.3048)
			(stroke
				(width 0.1)
				(type default)
			)
			(layer "F.Fab")
		)
		(fp_line
			(start 0.508 -0.3048)
			(end -0.508 -0.3048)
			(stroke
				(width 0.1)
				(type default)
			)
			(layer "F.Fab")
		)
		(fp_line
			(start 0.508 0.3048)
			(end 0.508 -0.3048)
			(stroke
				(width 0.1)
				(type default)
			)
			(layer "F.Fab")
		)
		(pad "1" smd rect
			(at -0.5334 0)
			(size 0.7112 0.6096)
			(layers "F.Cu" "F.Mask" "F.Paste")
			(net "MAC_ALARM")
		)
		(pad "2" smd rect
			(at 0.5334 0)
			(size 0.7112 0.6096)
			(layers "F.Cu" "F.Mask" "F.Paste")
			(net "FPGA_IN_MAC_ALARM_OUT_N")
		)
		(zone
			(layer "F.Cu")
			(hatch none 0.5)
			(connect_pads
				(clearance 0)
			)
			(min_thickness 0.25)
			(keepout
				(tracks allowed)
				(vias not_allowed)
				(pads allowed)
				(copperpour not_allowed)
				(footprints allowed)
			)
			(placement
				(enabled no)
				(sheetname "")
			)
			(fill
				(thermal_gap 0.5)
				(thermal_bridge_width 0.5)
				(island_removal_mode 0)
			)
			(polygon
				(pts
					(xy 79.8068 -42.7482) (xy 79.9592 -42.7482) (xy 79.9592 -43.3578) (xy 79.8068 -43.3578)
				)
			)
		)
	)
	(footprint ""
		(layer "F.Cu")
		(at 99.3648 -78.5368)
		(property "Reference" "C184"
			(at 2.78257 -1.4732 90)
			(unlocked yes)
			(layer "F.SilkS")
			(effects
				(font
					(size 0.7874 0.5842)
					(thickness 0.1524)
				)
			)
		)
		(property "Value" "VAL*"
			(at 0.0762 2.067306 0)
			(unlocked yes)
			(layer "F.Fab")
			(hide yes)
			(effects
				(font
					(size 0.7874 0.5842)
					(thickness 0.1524)
				)
			)
		)
		(property "Tolerance" "TOL*"
			(at 0.0762 3.032506 0)
			(unlocked yes)
			(layer "Cmts.User")
			(hide yes)
			(effects
				(font
					(size 0.7874 0.5842)
					(thickness 0.1524)
				)
			)
		)
		(property "User Part Number" "PARTNUM*"
			(at 0.1016 4.023106 0)
			(unlocked yes)
			(layer "Cmts.User")
			(hide yes)
			(effects
				(font
					(size 0.7874 0.5842)
					(thickness 0.1524)
				)
			)
		)
		(property "Device Type" "CAPACITOR-G105-0B104-EK,0.1UF,A"
			(at 0.0508 1.127506 0)
			(unlocked yes)
			(layer "F.Fab")
			(hide yes)
			(effects
				(font
					(size 0.7874 0.5842)
					(thickness 0.1524)
				)
			)
		)
		(duplicate_pad_numbers_are_jumpers no)
		(fp_line
			(start -1.143 -0.5588)
			(end -1.143 0.5588)
			(stroke
				(width 0.1)
				(type default)
			)
			(layer "F.SilkS")
		)
		(fp_line
			(start -1.143 0.5588)
			(end 1.143 0.5588)
			(stroke
				(width 0.1)
				(type default)
			)
			(layer "F.SilkS")
		)
		(fp_line
			(start 1.143 -0.5588)
			(end -1.143 -0.5588)
			(stroke
				(width 0.1)
				(type default)
			)
			(layer "F.SilkS")
		)
		(fp_line
			(start 1.143 0.5588)
			(end 1.143 -0.5588)
			(stroke
				(width 0.1)
				(type default)
			)
			(layer "F.SilkS")
		)
		(fp_rect
			(start -1.143 -0.5588)
			(end 1.143 0.5588)
			(stroke
				(width 0)
				(type default)
			)
			(fill no)
			(layer "F.CrtYd")
		)
		(fp_line
			(start -0.508 -0.3048)
			(end -0.508 0.3048)
			(stroke
				(width 0.1)
				(type default)
			)
			(layer "F.Fab")
		)
		(fp_line
			(start -0.508 0.3048)
			(end 0.508 0.3048)
			(stroke
				(width 0.1)
				(type default)
			)
			(layer "F.Fab")
		)
		(fp_line
			(start 0.508 -0.3048)
			(end -0.508 -0.3048)
			(stroke
				(width 0.1)
				(type default)
			)
			(layer "F.Fab")
		)
		(fp_line
			(start 0.508 0.3048)
			(end 0.508 -0.3048)
			(stroke
				(width 0.1)
				(type default)
			)
			(layer "F.Fab")
		)
		(pad "1" smd rect
			(at -0.5334 0)
			(size 0.7112 0.6096)
			(layers "F.Cu" "F.Mask" "F.Paste")
			(net "XP1R2V_EN_R")
		)
		(pad "2" smd rect
			(at 0.5334 0)
			(size 0.7112 0.6096)
			(layers "F.Cu" "F.Mask" "F.Paste")
			(net "SG")
		)
		(zone
			(layer "F.Cu")
			(hatch none 0.5)
			(connect_pads
				(clearance 0)
			)
			(min_thickness 0.25)
			(keepout
				(tracks allowed)
				(vias not_allowed)
				(pads allowed)
				(copperpour not_allowed)
				(footprints allowed)
			)
			(placement
				(enabled no)
				(sheetname "")
			)
			(fill
				(thermal_gap 0.5)
				(thermal_bridge_width 0.5)
				(island_removal_mode 0)
			)
			(polygon
				(pts
					(xy 99.2886 -78.8416) (xy 99.2886 -78.232) (xy 99.441 -78.232) (xy 99.441 -78.8416)
				)
			)
		)
	)
	(footprint ""
		(layer "F.Cu")
		(at 20.32 -33.02 180)
		(property "Reference" "R389"
			(at -2.667 -0.67437 0)
			(unlocked yes)
			(layer "F.SilkS")
			(effects
				(font
					(size 0.7874 0.5842)
					(thickness 0.1524)
				)
			)
		)
		(property "Value" "VAL*"
			(at 0.02032 2.13233 180)
			(unlocked yes)
			(layer "F.Fab")
			(hide yes)
			(effects
				(font
					(size 0.7874 0.5842)
					(thickness 0.1524)
				)
			)
		)
		(property "Tolerance" "TOL*"
			(at 0.044704 3.05435 180)
			(unlocked yes)
			(layer "Cmts.User")
			(hide yes)
			(effects
				(font
					(size 0.7874 0.5842)
					(thickness 0.1524)
				)
			)
		)
		(property "User Part Number" "PARTNUM*"
			(at 0.02032 4.024884 180)
			(unlocked yes)
			(layer "Cmts.User")
			(hide yes)
			(effects
				(font
					(size 0.7874 0.5842)
					(thickness 0.1524)
				)
			)
		)
		(property "Device Type" "RESISTOR-G155-133R0-01,33OHM,1%"
			(at 0.008382 1.210564 180)
			(unlocked yes)
			(layer "F.Fab")
			(hide yes)
			(effects
				(font
					(size 0.7874 0.5842)
					(thickness 0.1524)
				)
			)
		)
		(duplicate_pad_numbers_are_jumpers no)
		(fp_line
			(start 1.143 0.5588)
			(end 1.143 -0.5588)
			(stroke
				(width 0.1)
				(type default)
			)
			(layer "F.SilkS")
		)
		(fp_line
			(start 1.143 -0.5588)
			(end -1.143 -0.5588)
			(stroke
				(width 0.1)
				(type default)
			)
			(layer "F.SilkS")
		)
		(fp_line
			(start -1.143 0.5588)
			(end 1.143 0.5588)
			(stroke
				(width 0.1)
				(type default)
			)
			(layer "F.SilkS")
		)
		(fp_line
			(start -1.143 -0.5588)
			(end -1.143 0.5588)
			(stroke
				(width 0.1)
				(type default)
			)
			(layer "F.SilkS")
		)
		(fp_rect
			(start -1.143 -0.5588)
			(end 1.143 0.5588)
			(stroke
				(width 0)
				(type default)
			)
			(fill no)
			(layer "F.CrtYd")
		)
		(fp_line
			(start 0.508 0.3048)
			(end 0.508 -0.3048)
			(stroke
				(width 0.1)
				(type default)
			)
			(layer "F.Fab")
		)
		(fp_line
			(start 0.508 -0.3048)
			(end -0.508 -0.3048)
			(stroke
				(width 0.1)
				(type default)
			)
			(layer "F.Fab")
		)
		(fp_line
			(start -0.508 0.3048)
			(end 0.508 0.3048)
			(stroke
				(width 0.1)
				(type default)
			)
			(layer "F.Fab")
		)
		(fp_line
			(start -0.508 -0.3048)
			(end -0.508 0.3048)
			(stroke
				(width 0.1)
				(type default)
			)
			(layer "F.Fab")
		)
		(pad "1" smd rect
			(at -0.5334 0 180)
			(size 0.7112 0.6096)
			(layers "F.Cu" "F.Mask" "F.Paste")
			(net "SMA2_LED_GREEN_N")
		)
		(pad "2" smd rect
			(at 0.5334 0 180)
			(size 0.7112 0.6096)
			(layers "F.Cu" "F.Mask" "F.Paste")
			(net "UNNAMED_14_LED4PV14_I266_4")
		)
		(zone
			(layer "F.Cu")
			(hatch none 0.5)
			(connect_pads
				(clearance 0)
			)
			(min_thickness 0.25)
			(keepout
				(tracks not_allowed)
				(vias allowed)
				(pads allowed)
				(copperpour not_allowed)
				(footprints allowed)
			)
			(placement
				(enabled no)
				(sheetname "")
			)
			(fill
				(thermal_gap 0.5)
				(thermal_bridge_width 0.5)
				(island_removal_mode 0)
			)
			(polygon
				(pts
					(xy 20.3962 -32.7152) (xy 20.3962 -33.3248) (xy 20.2438 -33.3248) (xy 20.2438 -32.7152)
				)
			)
		)
		(zone
			(layer "F.Cu")
			(hatch none 0.5)
			(connect_pads
				(clearance 0)
			)
			(min_thickness 0.25)
			(keepout
				(tracks allowed)
				(vias not_allowed)
				(pads allowed)
				(copperpour not_allowed)
				(footprints allowed)
			)
			(placement
				(enabled no)
				(sheetname "")
			)
			(fill
				(thermal_gap 0.5)
				(thermal_bridge_width 0.5)
				(island_removal_mode 0)
			)
			(polygon
				(pts
					(xy 20.3962 -32.7152) (xy 20.3962 -33.3248) (xy 20.2438 -33.3248) (xy 20.2438 -32.7152)
				)
			)
		)
	)
	(footprint ""
		(layer "F.Cu")
		(at 39.6494 -95.9104)
		(property "Reference" "L7"
			(at -0.2032 1.46177 0)
			(unlocked yes)
			(layer "F.SilkS")
			(effects
				(font
					(size 0.7874 0.5842)
					(thickness 0.1524)
				)
				(justify left)
			)
		)
		(property "Value" "VAL*"
			(at -0.9398 3.70967 0)
			(unlocked yes)
			(layer "F.Fab")
			(hide yes)
			(effects
				(font
					(size 0.7874 0.5842)
					(thickness 0.1524)
				)
				(justify left)
			)
		)
		(property "Tolerance" "TOL*"
			(at -0.9906 5.00507 0)
			(unlocked yes)
			(layer "Cmts.User")
			(hide yes)
			(effects
				(font
					(size 0.7874 0.5842)
					(thickness 0.1524)
				)
				(justify left)
			)
		)
		(property "User Part Number" "PARTNUM*"
			(at -2.54 2.46507 0)
			(unlocked yes)
			(layer "Cmts.User")
			(hide yes)
			(effects
				(font
					(size 0.7874 0.5842)
					(thickness 0.1524)
				)
				(justify left)
			)
		)
		(property "Device Type" "FERRITEBEAD-G191-10101-01,26OHA"
			(at -0.9906 1.22047 0)
			(unlocked yes)
			(layer "F.Fab")
			(hide yes)
			(effects
				(font
					(size 0.7874 0.5842)
					(thickness 0.1524)
				)
				(justify left)
			)
		)
		(duplicate_pad_numbers_are_jumpers no)
		(fp_line
			(start -1.3208 -0.7112)
			(end 1.3208 -0.7112)
			(stroke
				(width 0.1)
				(type default)
			)
			(layer "F.SilkS")
		)
		(fp_line
			(start -1.3208 0.7112)
			(end -1.3208 -0.7112)
			(stroke
				(width 0.1)
				(type default)
			)
			(layer "F.SilkS")
		)
		(fp_line
			(start 1.3208 -0.7112)
			(end 1.3208 0.7112)
			(stroke
				(width 0.1)
				(type default)
			)
			(layer "F.SilkS")
		)
		(fp_line
			(start 1.3208 0.7112)
			(end -1.3208 0.7112)
			(stroke
				(width 0.1)
				(type default)
			)
			(layer "F.SilkS")
		)
		(fp_rect
			(start -1.3208 0.7112)
			(end 1.3208 -0.7112)
			(stroke
				(width 0)
				(type default)
			)
			(fill no)
			(layer "F.CrtYd")
		)
		(fp_line
			(start -0.8128 -0.4572)
			(end 0.8128 -0.4572)
			(stroke
				(width 0.1)
				(type default)
			)
			(layer "F.Fab")
		)
		(fp_line
			(start -0.8128 0.4572)
			(end -0.8128 -0.4572)
			(stroke
				(width 0.1)
				(type default)
			)
			(layer "F.Fab")
		)
		(fp_line
			(start 0.8128 -0.4572)
			(end 0.8128 0.4572)
			(stroke
				(width 0.1)
				(type default)
			)
			(layer "F.Fab")
		)
		(fp_line
			(start 0.8128 0.4572)
			(end -0.8128 0.4572)
			(stroke
				(width 0.1)
				(type default)
			)
			(layer "F.Fab")
		)
		(pad "1" smd rect
			(at -0.6858 0)
			(size 0.762 0.8636)
			(layers "F.Cu" "F.Mask" "F.Paste")
			(net "XP12R0V")
		)
		(pad "2" smd rect
			(at 0.6858 0)
			(size 0.762 0.8636)
			(layers "F.Cu" "F.Mask" "F.Paste")
			(net "VIN_XP5R0V")
		)
		(zone
			(layer "F.Cu")
			(hatch none 0.5)
			(connect_pads
				(clearance 0)
			)
			(min_thickness 0.25)
			(keepout
				(tracks allowed)
				(vias not_allowed)
				(pads allowed)
				(copperpour not_allowed)
				(footprints allowed)
			)
			(placement
				(enabled no)
				(sheetname "")
			)
			(fill
				(thermal_gap 0.5)
				(thermal_bridge_width 0.5)
				(island_removal_mode 0)
			)
			(polygon
				(pts
					(xy 39.497 -95.4532) (xy 39.8018 -95.4532) (xy 39.8018 -96.3676) (xy 39.497 -96.3676)
				)
			)
		)
		(zone
			(layer "F.Cu")
			(hatch none 0.5)
			(connect_pads
				(clearance 0)
			)
			(min_thickness 0.25)
			(keepout
				(tracks not_allowed)
				(vias allowed)
				(pads allowed)
				(copperpour not_allowed)
				(footprints allowed)
			)
			(placement
				(enabled no)
				(sheetname "")
			)
			(fill
				(thermal_gap 0.5)
				(thermal_bridge_width 0.5)
				(island_removal_mode 0)
			)
			(polygon
				(pts
					(xy 39.497 -95.4532) (xy 39.8018 -95.4532) (xy 39.8018 -96.3676) (xy 39.497 -96.3676)
				)
			)
		)
	)
	(footprint ""
		(layer "F.Cu")
		(at 122.428 -53.975)
		(property "Reference" "TP45"
			(at -0.08763 -0.8128 90)
			(unlocked yes)
			(layer "F.SilkS")
			(effects
				(font
					(size 0.7874 0.5842)
					(thickness 0.1524)
				)
				(justify left)
			)
		)
		(property "Value" ""
			(at 0 0 0)
			(layer "F.Fab")
			(effects
				(font
					(size 1.27 1.27)
				)
			)
		)
		(property "Device Type" "TP_PIONT-TP010CT020B030_PTH-TPA"
			(at -1.341882 0.996696 0)
			(unlocked yes)
			(layer "F.Fab")
			(hide yes)
			(effects
				(font
					(size 0.7874 0.5842)
					(thickness 0.000001)
				)
				(justify left)
			)
		)
		(duplicate_pad_numbers_are_jumpers no)
		(fp_poly
			(pts
				(arc
					(start 0.889 0)
					(mid -0.889 0)
					(end 0.889 0)
				)
			)
			(stroke
				(width 0)
				(type default)
			)
			(fill no)
			(layer "B.CrtYd")
		)
		(fp_poly
			(pts
				(arc
					(start 0.889 0)
					(mid -0.889 0)
					(end 0.889 0)
				)
			)
			(stroke
				(width 0)
				(type default)
			)
			(fill no)
			(layer "F.CrtYd")
		)
		(pad "1" thru_hole circle
			(at 0 0)
			(size 0.508 0.508)
			(drill 0.254)
			(layers "*.Cu" "*.Mask")
			(remove_unused_layers no)
			(net "FPGA_PROGRAM_N")
			(clearance 0.1016)
			(padstack
				(mode front_inner_back)
				(layer "Inner"
					(shape circle)
					(size 0.508 0.508)
					(clearance 0.1016)
				)
				(layer "B.Cu"
					(shape circle)
					(size 0.762 0.762)
					(clearance -0.0254)
				)
			)
		)
	)
)
